# T6G (Grand Teton) — schematic parts with pin connectivity, parts 7890–8034 of 8303; source: Cadence DE-HDL packaged netlist (pstxprt.dat, pstxnet.dat, pstchip.dat)

R8096  Q_RES  100K 1% CHIP  pkg 0402LF  page 142 : 1 = OCP_V3_2_P3V3_R1_PWRGD ; 2 = GND
R8097  Q_RES  0 5% CHIP  pkg 0402LF  page 142 : 1 = OCP_V3_2_P3V3_R1_PWRGD ; 2 = OCP_V3_2_P3V3_PWRGD
R8098  Q_RES  10K 5% EMPTY  pkg 0402LF  page 147 : 1 = P3V3_E1S_0_R ; 2 = P3V3_E1S_PWRGD_0_R1
R8099  Q_RES  100K 1% CHIP  pkg 0402LF  page 147 : 1 = P3V3_E1S_PWRGD_0_R1 ; 2 = GND
R8100  Q_RES  0 5% CHIP  pkg 0402LF  page 147 : 1 = P3V3_E1S_PWRGD_0_R1 ; 2 = P3V3_E1S_PWRGD_0_R
R8101  Q_RES  0 5% CHIP  pkg 0402LF  page 150 : 1 = FM_AC_PWR_BTN_R_N ; 2 = FM_AC_PWR_BTN_N
R8102  Q_RES  0 5% CHIP  pkg 0402LF  page 240 : 1 = FM_AC_PWR_BTN_R_N ; 2 = FM_AC_PWR_BTN_PDB_N
R8103  Q_RES  8.45K 1% EMPTY  pkg 0402LF  page 242 : 1 = P3V3_AUX ; 2 = FM_AC_PWR_BTN_R_N
R8104  Q_RES  0 5% EMPTY  pkg 0402LF  page 242 : 1 = FM_AC_PWR_BTN_R_N ; 2 = FM_AC_PWR_BTN_PLD_N
R8105  Q_RES  0 5% EMPTY  pkg 0402LF  page 242 : 1 = FM_AC_PWR_BTN_PLD_ISO_R_N ; 2 = FM_AC_PWR_BTN_PLD_ISO_N
R8106  Q_RES  1K 1% CHIP  pkg 0402LF  page 242 : 1 = P3V3_AUX ; 2 = FM_AC_PWR_BTN_PLD_ISO_N
R8107  Q_RES  10K 1% EMPTY  pkg 0402LF  page 267 : 1 = P3V3_AUX ; 2 = OC_P2V5_COMP
R8108  Q_RES  160K 1% EMPTY  pkg 0402LF  page 267 : 1 = HSC_CSOUT ; 2 = HSC_OC_VOL
R8109  Q_RES  10K 1% EMPTY  pkg 0402LF  page 267 : 1 = HSC_OC_VOL ; 2 = GND
R8110  Q_RES  33.2 1% EMPTY  pkg 0402LF  page 267 : 1 = HSC_D_OC_R2 ; 2 = A_HSC_LOW_GATE
R8111  Q_RES  10K 1% EMPTY  pkg 0402LF  page 267 : 1 = P3V3_AUX ; 2 = A_HSC_LOW_GATE
R8112  Q_RES  1M 1% EMPTY  pkg 0402LF  page 267 : 1 = HSC_OC_VOL ; 2 = HSC_D_OC_R2
R8113  Q_RES  10K 1% CHIP  pkg 0402LF  page 268 : 1 = P3V3_AUX ; 2 = UV_ADR_P2V5_COMP
R8114  Q_RES  17.8K 1% CHIP  pkg 0402LF  page 268 : 1 = P12V_AUX ; 2 = P12V_AUX_UV_ADR_TRIGGER
R8115  Q_RES  5.11K 1% CHIP  pkg 0402LF  page 268 : 1 = P12V_AUX_UV_ADR_TRIGGER ; 2 = GND
R8116  Q_RES  0 5% EMPTY  pkg 0402LF  page 207 : 1 = PVDD11_S3_P0_OCP_N ; 2 = PVDD11_S3_P0_OCP_N_R
R8117  Q_RES  1M 1% CHIP  pkg 0402LF  page 268 : 1 = P12V_AUX_UV_ADR_TRIGGER ; 2 = FM_UV_ADR_TRIGGER_N_R2
R8118  Q_RES  33.2 1% CHIP  pkg 0402LF  page 268 : 1 = FM_UV_ADR_TRIGGER_N_R2 ; 2 = FM_UV_ADR_TRIGGER_N
R8119  Q_RES  1K 1% CHIP  pkg 0402LF  page 268 : 1 = P3V3_AUX ; 2 = FM_UV_ADR_TRIGGER_N
R8120  Q_RES  10K 1% CHIP  pkg 0402LF  page 268 : 1 = P3V3_AUX ; 2 = UV_P2V5_COMP
R8121  Q_RES  17.8K 1% CHIP  pkg 0402LF  page 268 : 1 = P12V_AUX ; 2 = P12V_AUX_UV_TRIGGER
R8122  Q_RES  5.11K 1% CHIP  pkg 0402LF  page 268 : 1 = P12V_AUX_UV_TRIGGER ; 2 = GND
R8123  Q_RES  1M 1% CHIP  pkg 0402LF  page 268 : 1 = P12V_AUX_UV_TRIGGER ; 2 = IRQ_UV_DETECT_R2_N
R8124  Q_RES  33.2 1% CHIP  pkg 0402LF  page 268 : 1 = IRQ_UV_DETECT_R2_N ; 2 = IRQ_UV_DETECT_N
R8125  Q_RES  1K 1% CHIP  pkg 0402LF  page 268 : 1 = P3V3_AUX ; 2 = IRQ_UV_DETECT_N
R8146  Q_RES  0 5% EMPTY  pkg 0402LF  page 224 : 1 = P3V3_AUX ; 2 = PVDD11_S3_P1_VDDIO
R8153  Q_RES  1K 1% EMPTY  pkg 0402LF  page 210 : 1 = SVID_PVDDCR_CPU0_P1_SVTO ; 2 = GND
R8156  Q_RES  1K 1% EMPTY  pkg 0402LF  page 210 : 1 = PVDD18_S5_P1 ; 2 = SVID_PVDDCR_CPU0_P1_SVD_R
R8160  Q_RES  1K 1% EMPTY  pkg 0402LF  page 210 : 1 = PVDD18_S5_P1 ; 2 = SVID_PVDDCR_CPU0_P1_SVC_R
R8165  Q_RES  1K 1% CHIP  pkg 0402LF  page 210 : 1 = P3V3_AUX ; 2 = PWRGD_PVDDCR_SOC_P1_R
R8166  Q_RES  33 5% CHIP  pkg 0402LF  page 210 : 1 = PWRGD_PVDDCR_SOC_P1 ; 2 = PWRGD_PVDDCR_SOC_P1_R
R8167  Q_RES  1K 1% CHIP  pkg 0402LF  page 210 : 1 = P3V3_AUX ; 2 = PWRGD_PVDDCR_CPU0_P1_R
R8168  Q_RES  0 5% CHIP  pkg 0402LF  page 210 : 1 = PVDDCR_CPU0_P1_OCP_N ; 2 = PVDDCR_CPU0_P1_OCP_N_R
R8171  Q_RES  49.9 1% CHIP  pkg 0402LF  page 210 : 1 = SVID_PVDDCR_CPU0_P1_SVTO ; 2 = SVID_PVDDCR_CPU0_P1_SVTO_R
R8176  Q_RES  0 5% CHIP  pkg 0402LF  page 210 : 1 = SMB_VR_3V3STBY_SDA ; 2 = PVDDCR_CPU0_P1_PMSDA_R
R8177  Q_RES  33 5% CHIP  pkg 0402LF  page 210 : 1 = PVDDCR_CPU0_P1_PMALERT ; 2 = PVDDCR_CPU0_P1_PMALERT_R
R8178  Q_RES  33 5% CHIP  pkg 0402LF  page 210 : 1 = PWRGD_PVDDCR_CPU0_P1 ; 2 = PWRGD_PVDDCR_CPU0_P1_R
R8179  Q_RES  0 5% CHIP  pkg 0402LF  page 210 : 1 = PVDDCR_CPU0_P1_EN ; 2 = PVDDCR_CPU0_P1_EN_R
R8180  Q_RES  1K 1% CHIP  pkg 0402LF  page 210 : 1 = PVDD18_S5_P1 ; 2 = PVDDCR_CPU0_P1_OCP_N_R
R8182  Q_RES  49.9 1% CHIP  pkg 0402LF  page 210 : 1 = PVDDCR_CPU0_P1_RESET_N ; 2 = PVDDCR_CPU0_P1_RESET_N_R
R8184  Q_RES  1K 1% CHIP  pkg 0402LF  page 210 : 1 = PVDD18_S5_P1 ; 2 = PVDDCR_CPU0_P1_RESET_N_R
R8219  Q_RES  1K 1% EMPTY  pkg 0402LF  page 217 : 1 = SVID_PVDDCR_CPU1_P1_SVTO ; 2 = GND
R8220  Q_RES  1K 1% EMPTY  pkg 0402LF  page 217 : 1 = PVDD18_S5_P1 ; 2 = SVID_PVDDCR_CPU1_P1_SVTO
R8222  Q_RES  1K 1% EMPTY  pkg 0402LF  page 217 : 1 = PVDD18_S5_P1 ; 2 = SVID_PVDDCR_CPU1_P1_SVD_R
R8224  Q_RES  0 5% CHIP  pkg 0402LF  page 217 : 1 = PVDDIO_P1_EN ; 2 = PVDDIO_P1_EN_R
R8225  Q_RES  1K 1% EMPTY  pkg 0402LF  page 217 : 1 = PVDD18_S5_P1 ; 2 = SVID_PVDDCR_CPU1_P1_SVC_R
R8233  Q_RES  1K 1% CHIP  pkg 0402LF  page 217 : 1 = P3V3_AUX ; 2 = PWRGD_PVDDCR_CPU1_P1_R
R8234  Q_RES  33 5% CHIP  pkg 0402LF  page 217 : 1 = PWRGD_PVDDCR_CPU1_P1 ; 2 = PWRGD_PVDDCR_CPU1_P1_R
R8235  Q_RES  0 5% CHIP  pkg 0402LF  page 217 : 1 = FM_PVDDCR_CPU1_P1_EN ; 2 = PVDDCR_CPU1_P1_EN_R
R8238  Q_RES  49.9 1% CHIP  pkg 0402LF  page 217 : 1 = SVID_PVDDCR_CPU1_P1_SVTO ; 2 = SVID_PVDDCR_CPU1_P1_SVTO_R
R8241  Q_RES  0 5% CHIP  pkg 0402LF  page 217 : 1 = PVDDCR_CPU1_P1_OCP_N ; 2 = PVDDCR_CPU1_P1_OCP_N_R
R8242  Q_RES  1K 1% CHIP  pkg 0402LF  page 217 : 1 = P3V3_AUX ; 2 = PWRGD_PVDDIO_P1_R
R8243  Q_RES  33 5% CHIP  pkg 0402LF  page 217 : 1 = PWRGD_PVDDIO_P1 ; 2 = PWRGD_PVDDIO_P1_R
R8247  Q_RES  1K 1% CHIP  pkg 0402LF  page 217 : 1 = PVDD18_S5_P1 ; 2 = PVDDCR_CPU1_P1_RESET_N_R
R8248  Q_RES  0 5% CHIP  pkg 0402LF  page 217 : 1 = SMB_SCM_2_R1_SCL ; 2 = SMB_CLK_PVDDCR_CPU1_P1_R
R8249  Q_RES  0 5% CHIP  pkg 0402LF  page 217 : 1 = SMB_SCM_2_R1_SDA ; 2 = SMB_DIO_PVDDCR_CPU1_P1_R
R8250  Q_RES  33 5% CHIP  pkg 0402LF  page 217 : 1 = PVDDCR_CPU1_P1_SMB_ALERT ; 2 = PVDDCR_CPU1_P1_SMB_ALERT_R
R8252  Q_RES  1K 1% CHIP  pkg 0402LF  page 217 : 1 = PVDD18_S5_P1 ; 2 = PVDDCR_CPU1_P1_OCP_N_R
R8282  Q_RES  0 5% CHIP  pkg 0402LF  page 193 : 1 = PVDDCR_SOC_P0_EN ; 2 = PVDDCR_SOC_P0_EN_RC
R8286  Q_RES  1K 1% EMPTY  pkg 0402LF  page 193 : 1 = SVID_PVDDCR_CPU0_P0_SVTO ; 2 = GND
R8287  Q_RES  1K 1% EMPTY  pkg 0402LF  page 193 : 1 = PVDD18_S5_P0 ; 2 = SVID_PVDDCR_CPU0_P0_SVTO
R8289  Q_RES  1K 1% EMPTY  pkg 0402LF  page 193 : 1 = PVDD18_S5_P0 ; 2 = SVID_PVDDCR_CPU0_P0_SVD_R
R8293  Q_RES  1K 1% EMPTY  pkg 0402LF  page 193 : 1 = PVDD18_S5_P0 ; 2 = SVID_PVDDCR_CPU0_P0_SVC_R
R8298  Q_RES  1K 1% CHIP  pkg 0402LF  page 193 : 1 = P3V3_AUX ; 2 = PWRGD_PVDDCR_SOC_P0_R
R8299  Q_RES  33 5% CHIP  pkg 0402LF  page 193 : 1 = PWRGD_PVDDCR_SOC_P0 ; 2 = PWRGD_PVDDCR_SOC_P0_R
R8300  Q_RES  1K 1% CHIP  pkg 0402LF  page 193 : 1 = P3V3_AUX ; 2 = PWRGD_PVDDCR_CPU0_P0_R
R8301  Q_RES  0 5% CHIP  pkg 0402LF  page 193 : 1 = PVDDCR_CPU0_P0_OCP_N ; 2 = PVDDCR_CPU0_P0_OCP_N_R
R8304  Q_RES  49.9 1% CHIP  pkg 0402LF  page 193 : 1 = SVID_PVDDCR_CPU0_P0_SVTO ; 2 = SVID_PVDDCR_CPU0_P0_SVTO_R
R8305  Q_RES  0 5% CHIP  pkg 0402LF  page 28 : 1 = CLK_100M_CPU0_CLK13_R_DP ; 2 = CLK_100M_CPU0_CLK13_DP
R8306  Q_RES  0 5% CHIP  pkg 0402LF  page 28 : 1 = CLK_100M_CPU0_CLK13_R_DN ; 2 = CLK_100M_CPU0_CLK13_DN
R8308  Q_RES  0 5% CHIP  pkg 0402LF  page 193 : 1 = SMB_SCM_2_R3_SCL ; 2 = PVDDCR_CPU0_P0_PMSCL_R
R8309  Q_RES  0 5% CHIP  pkg 0402LF  page 193 : 1 = SMB_SCM_2_R3_SDA ; 2 = PVDDCR_CPU0_P0_PMSDA_R
R8310  Q_RES  33 5% CHIP  pkg 0402LF  page 193 : 1 = PVDDCR_CPU0_P0_PMALERT ; 2 = PVDDCR_CPU0_P0_PMALERT_R
R8311  Q_RES  33 5% CHIP  pkg 0402LF  page 193 : 1 = PWRGD_PVDDCR_CPU0_P0 ; 2 = PWRGD_PVDDCR_CPU0_P0_R
R8312  Q_RES  0 5% CHIP  pkg 0402LF  page 193 : 1 = PVDDCR_CPU0_P0_EN ; 2 = PVDDCR_CPU0_P0_EN_R
R8313  Q_RES  1K 1% CHIP  pkg 0402LF  page 193 : 1 = PVDD18_S5_P0 ; 2 = PVDDCR_CPU0_P0_OCP_N_R
R8317  Q_RES  1K 1% CHIP  pkg 0402LF  page 193 : 1 = PVDD18_S5_P0 ; 2 = PVDDCR_CPU0_P0_RESET_N_R
R8350  Q_RES  0 5% CHIP  pkg 0402LF  page 55 : 1 = CLK_100M_CPU1_CLK13_R_DP ; 2 = CLK_100M_CPU1_CLK13_DP
R8351  Q_RES  0 5% CHIP  pkg 0402LF  page 55 : 1 = CLK_100M_CPU1_CLK13_R_DN ; 2 = CLK_100M_CPU1_CLK13_DN
R8380  Q_RES  1K 1% CHIP  pkg 0402LF  page 224 : 1 = P3V3_AUX ; 2 = PWRGD_PVDD11_S3_P1_R
R8381  Q_RES  0 5% CHIP  pkg 0402LF  page 224 : 1 = SMB_SCM_2_R2_SCL ; 2 = PVDD11_S3_P1_PMSCL_R
R8382  Q_RES  0 5% CHIP  pkg 0402LF  page 224 : 1 = SMB_SCM_2_R2_SDA ; 2 = PVDD11_S3_P1_PMSDA_R
R8383  Q_RES  33 5% CHIP  pkg 0402LF  page 224 : 1 = PVDD11_S3_P1_PMALERT ; 2 = PVDD11_S3_P1_PMALERT_R
R8385  Q_RES  0 5% CHIP  pkg 0402LF  page 224 : 1 = PWRGD_PVDD11_S3_P1 ; 2 = PWRGD_PVDD11_S3_P1_R
R8386  Q_RES  0 5% CHIP  pkg 0402LF  page 224 : 1 = PVDD11_S3_P1_EN ; 2 = PVDD11_S3_P1_EN_R
R8413  Q_RES  100K 1% CHIP  pkg 0402LF  page 137 : 1 = GND ; 2 = FM_OCP_V3_2_PWR_GOOD
R8420  Q_RES  1K 1% CHIP  pkg 0402LF  page 131 : 1 = SGPIO_OCP_SFF_LD_N ; 2 = P3V3_OCP_SFF
R8421  Q_RES  10K 1% CHIP  pkg 0402LF  page 131 : 1 = SGPIO_OCP_SFF_DATAIN ; 2 = P3V3_OCP_SFF
R8422  Q_RES  10K 1% CHIP  pkg 0402LF  page 131 : 1 = SGPIO_OCP_SFF_DATAOUT ; 2 = GND
R8423  Q_RES  1K 1% CHIP  pkg 0402LF  page 131 : 1 = SGPIO_OCP_SFF_CLK ; 2 = P3V3_OCP_SFF
R8458  Q_RES  0 5% EMPTY  pkg 0402LF  page 207 : 1 = P3V3_AUX ; 2 = PVDD11_S3_P0_VDDIO
R8465  Q_RES  10K 5% CHIP  pkg 0402LF  page 209 : 1 = P3V3_AUX ; 2 = PWRGD_PVDD18_S5_P0
R8563  Q_RES  0 5% CHIP  pkg 0402LF  page 28 : 1 = CLK_100M_CPU0_CLK02_R_DP ; 2 = CLK_100M_CPU0_CLK02_DP
R8564  Q_RES  0 5% CHIP  pkg 0402LF  page 28 : 1 = CLK_100M_CPU0_CLK02_R_DN ; 2 = CLK_100M_CPU0_CLK02_DN
R8565  Q_RES  0 5% CHIP  pkg 0402LF  page 28 : 1 = CLK_100M_CPU0_CLK03_R_DP ; 2 = CLK_100M_CPU0_CLK03_DP
R8566  Q_RES  0 5% CHIP  pkg 0402LF  page 28 : 1 = CLK_100M_CPU0_CLK03_R_DN ; 2 = CLK_100M_CPU0_CLK03_DN
R9000  Q_RES  1K 1% CHIP  pkg 0402LF  page 240 : 1 = P3V3_AUX ; 2 = FM_FAN_PWR_EN
R9001  Q_RES  0 5% CHIP  pkg 0402LF  page 245 : 1 = GPU_PRSNT_N_ISO ; 2 = GPU_PRSNT_N_ISO_R1
R9002  Q_RES  10K 1% CHIP  pkg 0402LF  page 123 : 1 = P3V3_AUX ; 2 = PRSNT_CABLE_SWB_B1_N
R9003  Q_RES  100K 1% EMPTY  pkg 0402LF  page 123 : 1 = PRSNT_CABLE_SWB_B1_N ; 2 = GND
R9004  Q_RES  4.7K 5% CHIP  pkg 0402LF  page 123 : 1 = P3V3_AUX ; 2 = PRSNT_CABLE_SWB_B1
R9005  Q_RES  4.7K 5% CHIP  pkg 0402LF  page 123 : 1 = P3V3_AUX ; 2 = PRSNT_CABLE_SWB_B1_ISO_N
R9006  Q_RES  10K 1% CHIP  pkg 0402LF  page 123 : 1 = P3V3_AUX ; 2 = PRSNT_CABLE_SWB_B2_N
R9007  Q_RES  100K 1% EMPTY  pkg 0402LF  page 123 : 1 = PRSNT_CABLE_SWB_B2_N ; 2 = GND
R9008  Q_RES  4.7K 5% CHIP  pkg 0402LF  page 123 : 1 = P3V3_AUX ; 2 = PRSNT_CABLE_SWB_B2
R9009  Q_RES  4.7K 5% CHIP  pkg 0402LF  page 123 : 1 = P3V3_AUX ; 2 = PRSNT_CABLE_SWB_B2_ISO_N
R9010  Q_RES  0 5% CHIP  pkg 0402LF  page 245 : 1 = PRSNT_CABLE_SWB_B1_ISO_N ; 2 = PRSNT_CABLE_SWB_B1_ISO_R_N
R9011  Q_RES  0 5% CHIP  pkg 0402LF  page 245 : 1 = PRSNT_CABLE_GPU_B3_ISO_N ; 2 = PRSNT_CABLE_GPU_B3_ISO_R1_N
R9012  Q_RES  0 5% CHIP  pkg 0402LF  page 245 : 1 = PRSNT_CABLE_SWB_B2_ISO_N ; 2 = PRSNT_CABLE_SWB_B2_ISO_R_N
R9013  Q_RES  0 5% CHIP  pkg 0402LF  page 245 : 1 = PRSNT_CABLE_GPU_A2_ISO_N ; 2 = PRSNT_CABLE_GPU_A2_ISO_R1_N
R9014  Q_RES  10K 1% CHIP  pkg 0402LF  page 123 : 1 = P3V3_AUX ; 2 = PRSNT_CABLE_GPU_A3_N
R9015  Q_RES  100K 1% EMPTY  pkg 0402LF  page 123 : 1 = PRSNT_CABLE_GPU_A3_N ; 2 = GND
R9016  Q_RES  4.7K 5% CHIP  pkg 0402LF  page 123 : 1 = P3V3_AUX ; 2 = PRSNT_CABLE_GPU_A3
R9017  Q_RES  4.7K 5% CHIP  pkg 0402LF  page 123 : 1 = P3V3_AUX ; 2 = PRSNT_CABLE_GPU_A3_ISO_N
R9018  Q_RES  0 5% CHIP  pkg 0402LF  page 245 : 1 = PRSNT_CABLE_GPU_A3_ISO_N ; 2 = PRSNT_CABLE_GPU_A3_ISO_R_N
R9019  Q_RES  0 5% CHIP  pkg 0402LF  page 245 : 1 = PRSNT_CABLE_GPU_A1_ISO_N ; 2 = PRSNT_CABLE_GPU_A1_ISO_R1_N
R9020  Q_RES  1K 1% EMPTY  pkg 0402LF  page 267 : 1 = P3V3_AUX ; 2 = U142_VS
R9021  Q_RES  1K 1% EMPTY  pkg 0402LF  page 268 : 1 = P12V_AUX ; 2 = U206_VS
R9022  Q_RES  33.2 1% CHIP  pkg 0402LF  page 136 : 1 = OCP_V3_1_P3V3_R3_PWRGD ; 2 = HP_LVC3_OCP_V3_1_PWRGD
R9023  Q_RES  33.2 1% CHIP  pkg 0402LF  page 136 : 1 = RST_PERST_OCP_SFF_N ; 2 = RST_PERST_OCP_SFF_R_N
R9024  Q_RES  54.9K 1% CHIP  pkg 0402LF  page 267 : 1 = P3V3_AUX ; 2 = IRQ_HSC_FAULT_N
R9025  Q_RES  100K 1% EMPTY  pkg 0402LF  page 85 : 1 = IRQ_HSC_FAULT_N ; 2 = GND
R9026  Q_RES  4.7K 5% CHIP  pkg 0402LF  page 85 : 1 = P3V3_AUX ; 2 = IRQ_HSC_FAULT
R9027  Q_RES  100K 1% CHIP  pkg 0402LF  page 85 : 1 = P3V3_AUX ; 2 = IRQ_HSC_FAULT_BUF_N
R9028  Q_RES  0 5% EMPTY  pkg 0402LF  page 85 : 1 = IRQ_HSC_FAULT_N ; 2 = IRQ_HSC_FAULT_BUF_N
R9029  Q_RES  0 5% EMPTY  pkg 0402LF  page 136 : 1 = OCP_SFF_AUX_PWR_EN_R3 ; 2 = HP_LVC3_OCP_V3_1_PWRGD_R1
R9030  Q_RES  0 5% EMPTY  pkg 0402LF  page 136 : 1 = OCP_SFF_AUX_PWR_EN_R3 ; 2 = FM_PLD_OCP_SFF_AUX_PWR_EN
R9031  Q_RES  33.2 1% CHIP  pkg 0402LF  page 136 : 1 = OCP_SFF_AUX_PWR_EN_R3 ; 2 = OCP_SFF_AUX_PWR_EN
R9032  Q_RES  10K 1% CHIP  pkg 0402LF  page 136 : 1 = P3V3_AUX ; 2 = FM_PLD_OCP_SFF_AUX_PWR_EN
R9033  Q_RES  33.2 1% CHIP  pkg 0402LF  page 136 : 1 = RST_PERST_OCP_SFF_BUF_R_N ; 2 = RST_PERST_OCP_SFF_BUF_N
R9034  Q_RES  33.2 1% CHIP  pkg 0402LF  page 136 : 1 = OCP_V3_1_P3V3_R3_PWRGD ; 2 = HP_LVC3_OCP_V3_1_PWRGD_R1
R9043  Q_RES  4.7K 5% CHIP  pkg 0402LF  page 126 : 1 = P3V3_AUX ; 2 = GPU_WP_HW_CTRL_ISO
R9044  Q_RES  4.7K 1% EMPTY  pkg 0402LF  page 126 : 1 = P3V3_AUX ; 2 = GPU_WP_HW_CTRL_ISO_N
R9273  Q_RES  0 5% CHIP  pkg 0402LF  page 28 : 1 = CLK_100M_CPU0_CLK04_R_DP ; 2 = CLK_100M_CPU0_CLK04_DP
R9274  Q_RES  0 5% CHIP  pkg 0402LF  page 28 : 1 = CLK_100M_CPU0_CLK04_R_DN ; 2 = CLK_100M_CPU0_CLK04_DN
R9275  Q_RES  0 5% CHIP  pkg 0402LF  page 28 : 1 = CLK_100M_CPU0_CLK05_R_DP ; 2 = CLK_100M_CPU0_CLK05_DP
R9276  Q_RES  0 5% CHIP  pkg 0402LF  page 28 : 1 = CLK_100M_CPU0_CLK05_R_DN ; 2 = CLK_100M_CPU0_CLK05_DN
R9446  Q_RES  33.2 1% CHIP  pkg 0402LF  page 253 : 1 = PWRGD_PS_PWROK_PLD_ISO ; 2 = PWRGD_PS_PWROK_PLD_ISO_R
R10287  Q_RES  10K 1% CHIP  pkg 0402LF  page 145 : 1 = P3V3_E1S_0 ; 2 = E1S_0_PERST1_CLKREQ_N
R10296  Q_RES  1K 1% CHIP  pkg 0402LF  page 145 : 1 = E1S_0_PWRDIS ; 2 = GND
